(kicad_pcb
	(version 20260206)
	(generator "pcbnew")
	(generator_version "10.0")
	(general
		(thickness 1.6)
		(legacy_teardrops no)
	)
	(paper "A4")
	(title_block
		(title "01162023_DA0F0TEBIF0_F0T_Expander_BD_F_brd_V02_OCP.brd")
		(comment 1 "Grand Teton / footprints 2383-2388 of 9728")
	)
	(layers
		(0 "F.Cu" signal "TOP")
		(4 "In1.Cu" signal "GND")
		(6 "In2.Cu" signal "VCC")
		(8 "In3.Cu" signal "VCC1")
		(10 "In4.Cu" signal "GND1")
		(12 "In5.Cu" signal "IN1")
		(14 "In6.Cu" signal "GND2")
		(16 "In7.Cu" signal "IN2")
		(18 "In8.Cu" signal "GND3")
		(20 "In9.Cu" signal "IN3")
		(22 "In10.Cu" signal "GND4")
		(24 "In11.Cu" signal "IN4")
		(26 "In12.Cu" signal "GND5")
		(28 "In13.Cu" signal "IN5")
		(30 "In14.Cu" signal "GND6")
		(32 "In15.Cu" signal "IN6")
		(34 "In16.Cu" signal "GND7")
		(2 "B.Cu" signal "BOTTOM")
		(9 "F.Adhes" user "F.Adhesive")
		(11 "B.Adhes" user "B.Adhesive")
		(13 "F.Paste" user "Package Geometry/Pastemask Top")
		(15 "B.Paste" user "Package Geometry/Pastemask Bottom")
		(5 "F.SilkS" user "Ref Des/Silkscreen Top")
		(7 "B.SilkS" user "Ref Des/Silkscreen Bottom")
		(1 "F.Mask" user "Board Geometry/Soldermask Top")
		(3 "B.Mask" user "Board Geometry/Soldermask Bottom")
		(17 "Dwgs.User" user "User.Drawings")
		(19 "Cmts.User" user "User.Comments")
		(21 "Eco1.User" user "User.Eco1")
		(23 "Eco2.User" user "User.Eco2")
		(25 "Edge.Cuts" user "Board Geometry/Outline")
		(27 "Margin" user)
		(31 "F.CrtYd" user "Package Geometry/Place Bound Top")
		(29 "B.CrtYd" user "Package Geometry/Place Bound Bottom")
		(35 "F.Fab" user "Ref Des/Assembly Top")
		(33 "B.Fab" user "Ref Des/Assembly Bottom")
	)
	(footprint ""
		(layer "F.Cu")
		(at 361.89031 -253.178564 180)
		(property "Reference" "R834"
			(at 0 0 180)
			(layer "F.SilkS")
			(hide yes)
			(effects
				(font
					(size 1.27 1.27)
				)
			)
		)
		(property "Value" ""
			(at 0 0 180)
			(layer "F.Fab")
			(effects
				(font
					(size 1.27 1.27)
				)
			)
		)
		(duplicate_pad_numbers_are_jumpers no)
		(fp_line
			(start 0.7874 0.4064)
			(end -0.7874 0.4064)
			(stroke
				(width 0.1524)
				(type default)
			)
			(layer "F.SilkS")
		)
		(fp_line
			(start 0.7874 -0.4064)
			(end 0.7874 0.4064)
			(stroke
				(width 0.1524)
				(type default)
			)
			(layer "F.SilkS")
		)
		(fp_line
			(start -0.7874 0.4064)
			(end -0.7874 -0.4064)
			(stroke
				(width 0.1524)
				(type default)
			)
			(layer "F.SilkS")
		)
		(fp_line
			(start -0.7874 -0.4064)
			(end 0.7874 -0.4064)
			(stroke
				(width 0.1524)
				(type default)
			)
			(layer "F.SilkS")
		)
		(fp_line
			(start 0.67945 0.3048)
			(end 0.120396 0.3048)
			(stroke
				(width 0.1)
				(type default)
			)
			(layer "F.Fab")
		)
		(fp_line
			(start 0.67945 -0.3048)
			(end 0.67945 0.3048)
			(stroke
				(width 0.1)
				(type default)
			)
			(layer "F.Fab")
		)
		(fp_line
			(start 0.12065 -0.2794)
			(end 0.12065 -0.3048)
			(stroke
				(width 0.1)
				(type default)
			)
			(layer "F.Fab")
		)
		(fp_line
			(start 0.12065 -0.3048)
			(end 0.67945 -0.3048)
			(stroke
				(width 0.1)
				(type default)
			)
			(layer "F.Fab")
		)
		(fp_line
			(start 0.120396 0.3048)
			(end 0.120396 0.2794)
			(stroke
				(width 0.1)
				(type default)
			)
			(layer "F.Fab")
		)
		(fp_line
			(start 0.120396 0.2794)
			(end -0.12065 0.2794)
			(stroke
				(width 0.1)
				(type default)
			)
			(layer "F.Fab")
		)
		(fp_line
			(start -0.12065 0.3048)
			(end -0.67945 0.3048)
			(stroke
				(width 0.1)
				(type default)
			)
			(layer "F.Fab")
		)
		(fp_line
			(start -0.12065 0.2794)
			(end -0.12065 0.3048)
			(stroke
				(width 0.1)
				(type default)
			)
			(layer "F.Fab")
		)
		(fp_line
			(start -0.12065 -0.2794)
			(end 0.12065 -0.2794)
			(stroke
				(width 0.1)
				(type default)
			)
			(layer "F.Fab")
		)
		(fp_line
			(start -0.12065 -0.305054)
			(end -0.12065 -0.2794)
			(stroke
				(width 0.1)
				(type default)
			)
			(layer "F.Fab")
		)
		(fp_line
			(start -0.67945 0.3048)
			(end -0.67945 -0.305054)
			(stroke
				(width 0.1)
				(type default)
			)
			(layer "F.Fab")
		)
		(fp_line
			(start -0.67945 -0.305054)
			(end -0.12065 -0.305054)
			(stroke
				(width 0.1)
				(type default)
			)
			(layer "F.Fab")
		)
		(pad "1" smd circle
			(at -0.40005 0 180)
			(size 0 0)
			(layers "F.Cu" "F.Mask" "F.Paste")
			(net "PWRGD_P0V8_PEX2_R")
		)
		(pad "2" smd circle
			(at 0.40005 0 180)
			(size 0 0)
			(layers "F.Cu" "F.Mask" "F.Paste")
			(net "P0V8_PEX2_AVRRDY")
		)
	)
	(footprint ""
		(layer "F.Cu")
		(at 423.95648 -20.467574 180)
		(property "Reference" "R1731"
			(at 0 0 180)
			(layer "F.SilkS")
			(hide yes)
			(effects
				(font
					(size 1.27 1.27)
				)
			)
		)
		(property "Value" ""
			(at 0 0 180)
			(layer "F.Fab")
			(effects
				(font
					(size 1.27 1.27)
				)
			)
		)
		(duplicate_pad_numbers_are_jumpers no)
		(fp_line
			(start 0.7874 0.4064)
			(end -0.7874 0.4064)
			(stroke
				(width 0.1524)
				(type default)
			)
			(layer "F.SilkS")
		)
		(fp_line
			(start 0.7874 -0.4064)
			(end 0.7874 0.4064)
			(stroke
				(width 0.1524)
				(type default)
			)
			(layer "F.SilkS")
		)
		(fp_line
			(start -0.7874 0.4064)
			(end -0.7874 -0.4064)
			(stroke
				(width 0.1524)
				(type default)
			)
			(layer "F.SilkS")
		)
		(fp_line
			(start -0.7874 -0.4064)
			(end 0.7874 -0.4064)
			(stroke
				(width 0.1524)
				(type default)
			)
			(layer "F.SilkS")
		)
		(fp_line
			(start 0.67945 0.3048)
			(end 0.120396 0.3048)
			(stroke
				(width 0.1)
				(type default)
			)
			(layer "F.Fab")
		)
		(fp_line
			(start 0.67945 -0.3048)
			(end 0.67945 0.3048)
			(stroke
				(width 0.1)
				(type default)
			)
			(layer "F.Fab")
		)
		(fp_line
			(start 0.12065 -0.2794)
			(end 0.12065 -0.3048)
			(stroke
				(width 0.1)
				(type default)
			)
			(layer "F.Fab")
		)
		(fp_line
			(start 0.12065 -0.3048)
			(end 0.67945 -0.3048)
			(stroke
				(width 0.1)
				(type default)
			)
			(layer "F.Fab")
		)
		(fp_line
			(start 0.120396 0.3048)
			(end 0.120396 0.2794)
			(stroke
				(width 0.1)
				(type default)
			)
			(layer "F.Fab")
		)
		(fp_line
			(start 0.120396 0.2794)
			(end -0.12065 0.2794)
			(stroke
				(width 0.1)
				(type default)
			)
			(layer "F.Fab")
		)
		(fp_line
			(start -0.12065 0.3048)
			(end -0.67945 0.3048)
			(stroke
				(width 0.1)
				(type default)
			)
			(layer "F.Fab")
		)
		(fp_line
			(start -0.12065 0.2794)
			(end -0.12065 0.3048)
			(stroke
				(width 0.1)
				(type default)
			)
			(layer "F.Fab")
		)
		(fp_line
			(start -0.12065 -0.2794)
			(end 0.12065 -0.2794)
			(stroke
				(width 0.1)
				(type default)
			)
			(layer "F.Fab")
		)
		(fp_line
			(start -0.12065 -0.305054)
			(end -0.12065 -0.2794)
			(stroke
				(width 0.1)
				(type default)
			)
			(layer "F.Fab")
		)
		(fp_line
			(start -0.67945 0.3048)
			(end -0.67945 -0.305054)
			(stroke
				(width 0.1)
				(type default)
			)
			(layer "F.Fab")
		)
		(fp_line
			(start -0.67945 -0.305054)
			(end -0.12065 -0.305054)
			(stroke
				(width 0.1)
				(type default)
			)
			(layer "F.Fab")
		)
		(pad "1" smd circle
			(at -0.40005 0 180)
			(size 0 0)
			(layers "F.Cu" "F.Mask" "F.Paste")
			(net "P3V3_SSD14")
		)
		(pad "2" smd circle
			(at 0.40005 0 180)
			(size 0 0)
			(layers "F.Cu" "F.Mask" "F.Paste")
			(net "SMB_ISO_SSD14_SDA")
		)
	)
	(footprint ""
		(layer "F.Cu")
		(at 385.304792 -141.87297 180)
		(property "Reference" "R337"
			(at 0 0 180)
			(layer "F.SilkS")
			(hide yes)
			(effects
				(font
					(size 1.27 1.27)
				)
			)
		)
		(property "Value" ""
			(at 0 0 180)
			(layer "F.Fab")
			(effects
				(font
					(size 1.27 1.27)
				)
			)
		)
		(duplicate_pad_numbers_are_jumpers no)
		(fp_line
			(start 0.7874 0.4064)
			(end -0.7874 0.4064)
			(stroke
				(width 0.1524)
				(type default)
			)
			(layer "F.SilkS")
		)
		(fp_line
			(start 0.7874 -0.4064)
			(end 0.7874 0.4064)
			(stroke
				(width 0.1524)
				(type default)
			)
			(layer "F.SilkS")
		)
		(fp_line
			(start -0.7874 0.4064)
			(end -0.7874 -0.4064)
			(stroke
				(width 0.1524)
				(type default)
			)
			(layer "F.SilkS")
		)
		(fp_line
			(start -0.7874 -0.4064)
			(end 0.7874 -0.4064)
			(stroke
				(width 0.1524)
				(type default)
			)
			(layer "F.SilkS")
		)
		(fp_line
			(start 0.67945 0.3048)
			(end 0.120396 0.3048)
			(stroke
				(width 0.1)
				(type default)
			)
			(layer "F.Fab")
		)
		(fp_line
			(start 0.67945 -0.3048)
			(end 0.67945 0.3048)
			(stroke
				(width 0.1)
				(type default)
			)
			(layer "F.Fab")
		)
		(fp_line
			(start 0.12065 -0.2794)
			(end 0.12065 -0.3048)
			(stroke
				(width 0.1)
				(type default)
			)
			(layer "F.Fab")
		)
		(fp_line
			(start 0.12065 -0.3048)
			(end 0.67945 -0.3048)
			(stroke
				(width 0.1)
				(type default)
			)
			(layer "F.Fab")
		)
		(fp_line
			(start 0.120396 0.3048)
			(end 0.120396 0.2794)
			(stroke
				(width 0.1)
				(type default)
			)
			(layer "F.Fab")
		)
		(fp_line
			(start 0.120396 0.2794)
			(end -0.12065 0.2794)
			(stroke
				(width 0.1)
				(type default)
			)
			(layer "F.Fab")
		)
		(fp_line
			(start -0.12065 0.3048)
			(end -0.67945 0.3048)
			(stroke
				(width 0.1)
				(type default)
			)
			(layer "F.Fab")
		)
		(fp_line
			(start -0.12065 0.2794)
			(end -0.12065 0.3048)
			(stroke
				(width 0.1)
				(type default)
			)
			(layer "F.Fab")
		)
		(fp_line
			(start -0.12065 -0.2794)
			(end 0.12065 -0.2794)
			(stroke
				(width 0.1)
				(type default)
			)
			(layer "F.Fab")
		)
		(fp_line
			(start -0.12065 -0.305054)
			(end -0.12065 -0.2794)
			(stroke
				(width 0.1)
				(type default)
			)
			(layer "F.Fab")
		)
		(fp_line
			(start -0.67945 0.3048)
			(end -0.67945 -0.305054)
			(stroke
				(width 0.1)
				(type default)
			)
			(layer "F.Fab")
		)
		(fp_line
			(start -0.67945 -0.305054)
			(end -0.12065 -0.305054)
			(stroke
				(width 0.1)
				(type default)
			)
			(layer "F.Fab")
		)
		(pad "1" smd circle
			(at -0.40005 0 180)
			(size 0 0)
			(layers "F.Cu" "F.Mask" "F.Paste")
			(net "NIC6_BIF1_N")
		)
		(pad "2" smd circle
			(at 0.40005 0 180)
			(size 0 0)
			(layers "F.Cu" "F.Mask" "F.Paste")
			(net "P3V3_AUX")
		)
	)
	(footprint ""
		(layer "F.Cu")
		(at 381.254 -208.534)
		(property "Reference" "R4602"
			(at 0 0 0)
			(layer "F.SilkS")
			(hide yes)
			(effects
				(font
					(size 1.27 1.27)
				)
			)
		)
		(property "Value" ""
			(at 0 0 0)
			(layer "F.Fab")
			(effects
				(font
					(size 1.27 1.27)
				)
			)
		)
		(duplicate_pad_numbers_are_jumpers no)
		(fp_line
			(start -0.7874 -0.4064)
			(end 0.7874 -0.4064)
			(stroke
				(width 0.1524)
				(type default)
			)
			(layer "F.SilkS")
		)
		(fp_line
			(start -0.7874 0.4064)
			(end -0.7874 -0.4064)
			(stroke
				(width 0.1524)
				(type default)
			)
			(layer "F.SilkS")
		)
		(fp_line
			(start 0.7874 -0.4064)
			(end 0.7874 0.4064)
			(stroke
				(width 0.1524)
				(type default)
			)
			(layer "F.SilkS")
		)
		(fp_line
			(start 0.7874 0.4064)
			(end -0.7874 0.4064)
			(stroke
				(width 0.1524)
				(type default)
			)
			(layer "F.SilkS")
		)
		(fp_line
			(start -0.67945 -0.305054)
			(end -0.12065 -0.305054)
			(stroke
				(width 0.1)
				(type default)
			)
			(layer "F.Fab")
		)
		(fp_line
			(start -0.67945 0.3048)
			(end -0.67945 -0.305054)
			(stroke
				(width 0.1)
				(type default)
			)
			(layer "F.Fab")
		)
		(fp_line
			(start -0.12065 -0.305054)
			(end -0.12065 -0.2794)
			(stroke
				(width 0.1)
				(type default)
			)
			(layer "F.Fab")
		)
		(fp_line
			(start -0.12065 -0.2794)
			(end 0.12065 -0.2794)
			(stroke
				(width 0.1)
				(type default)
			)
			(layer "F.Fab")
		)
		(fp_line
			(start -0.12065 0.2794)
			(end -0.12065 0.3048)
			(stroke
				(width 0.1)
				(type default)
			)
			(layer "F.Fab")
		)
		(fp_line
			(start -0.12065 0.3048)
			(end -0.67945 0.3048)
			(stroke
				(width 0.1)
				(type default)
			)
			(layer "F.Fab")
		)
		(fp_line
			(start 0.120396 0.2794)
			(end -0.12065 0.2794)
			(stroke
				(width 0.1)
				(type default)
			)
			(layer "F.Fab")
		)
		(fp_line
			(start 0.120396 0.3048)
			(end 0.120396 0.2794)
			(stroke
				(width 0.1)
				(type default)
			)
			(layer "F.Fab")
		)
		(fp_line
			(start 0.12065 -0.3048)
			(end 0.67945 -0.3048)
			(stroke
				(width 0.1)
				(type default)
			)
			(layer "F.Fab")
		)
		(fp_line
			(start 0.12065 -0.2794)
			(end 0.12065 -0.3048)
			(stroke
				(width 0.1)
				(type default)
			)
			(layer "F.Fab")
		)
		(fp_line
			(start 0.67945 -0.3048)
			(end 0.67945 0.3048)
			(stroke
				(width 0.1)
				(type default)
			)
			(layer "F.Fab")
		)
		(fp_line
			(start 0.67945 0.3048)
			(end 0.120396 0.3048)
			(stroke
				(width 0.1)
				(type default)
			)
			(layer "F.Fab")
		)
		(pad "1" smd circle
			(at -0.40005 0)
			(size 0 0)
			(layers "F.Cu" "F.Mask" "F.Paste")
			(net "P3V3_AUX")
		)
		(pad "2" smd circle
			(at 0.40005 0)
			(size 0 0)
			(layers "F.Cu" "F.Mask" "F.Paste")
			(net "NIC0_PEX_PWR_EN_R")
		)
	)
	(footprint ""
		(layer "F.Cu")
		(at 142.368016 -54.067456)
		(property "Reference" "PR210"
			(at 0 0 0)
			(layer "F.SilkS")
			(hide yes)
			(effects
				(font
					(size 1.27 1.27)
				)
			)
		)
		(property "Value" ""
			(at 0 0 0)
			(layer "F.Fab")
			(effects
				(font
					(size 1.27 1.27)
				)
			)
		)
		(duplicate_pad_numbers_are_jumpers no)
		(fp_line
			(start -0.7874 -0.4064)
			(end 0.7874 -0.4064)
			(stroke
				(width 0.1524)
				(type default)
			)
			(layer "F.SilkS")
		)
		(fp_line
			(start -0.7874 0.4064)
			(end -0.7874 -0.4064)
			(stroke
				(width 0.1524)
				(type default)
			)
			(layer "F.SilkS")
		)
		(fp_line
			(start 0.7874 -0.4064)
			(end 0.7874 0.4064)
			(stroke
				(width 0.1524)
				(type default)
			)
			(layer "F.SilkS")
		)
		(fp_line
			(start 0.7874 0.4064)
			(end -0.7874 0.4064)
			(stroke
				(width 0.1524)
				(type default)
			)
			(layer "F.SilkS")
		)
		(fp_line
			(start -0.67945 -0.305054)
			(end -0.12065 -0.305054)
			(stroke
				(width 0.1)
				(type default)
			)
			(layer "F.Fab")
		)
		(fp_line
			(start -0.67945 0.3048)
			(end -0.67945 -0.305054)
			(stroke
				(width 0.1)
				(type default)
			)
			(layer "F.Fab")
		)
		(fp_line
			(start -0.12065 -0.305054)
			(end -0.12065 -0.2794)
			(stroke
				(width 0.1)
				(type default)
			)
			(layer "F.Fab")
		)
		(fp_line
			(start -0.12065 -0.2794)
			(end 0.12065 -0.2794)
			(stroke
				(width 0.1)
				(type default)
			)
			(layer "F.Fab")
		)
		(fp_line
			(start -0.12065 0.2794)
			(end -0.12065 0.3048)
			(stroke
				(width 0.1)
				(type default)
			)
			(layer "F.Fab")
		)
		(fp_line
			(start -0.12065 0.3048)
			(end -0.67945 0.3048)
			(stroke
				(width 0.1)
				(type default)
			)
			(layer "F.Fab")
		)
		(fp_line
			(start 0.120396 0.2794)
			(end -0.12065 0.2794)
			(stroke
				(width 0.1)
				(type default)
			)
			(layer "F.Fab")
		)
		(fp_line
			(start 0.120396 0.3048)
			(end 0.120396 0.2794)
			(stroke
				(width 0.1)
				(type default)
			)
			(layer "F.Fab")
		)
		(fp_line
			(start 0.12065 -0.3048)
			(end 0.67945 -0.3048)
			(stroke
				(width 0.1)
				(type default)
			)
			(layer "F.Fab")
		)
		(fp_line
			(start 0.12065 -0.2794)
			(end 0.12065 -0.3048)
			(stroke
				(width 0.1)
				(type default)
			)
			(layer "F.Fab")
		)
		(fp_line
			(start 0.67945 -0.3048)
			(end 0.67945 0.3048)
			(stroke
				(width 0.1)
				(type default)
			)
			(layer "F.Fab")
		)
		(fp_line
			(start 0.67945 0.3048)
			(end 0.120396 0.3048)
			(stroke
				(width 0.1)
				(type default)
			)
			(layer "F.Fab")
		)
		(pad "1" smd circle
			(at -0.40005 0)
			(size 0 0)
			(layers "F.Cu" "F.Mask" "F.Paste")
			(net "P12V_SSD4_OCP")
		)
		(pad "2" smd circle
			(at 0.40005 0)
			(size 0 0)
			(layers "F.Cu" "F.Mask" "F.Paste")
			(net "GND")
		)
	)
	(footprint ""
		(layer "F.Cu")
		(at 387.132068 -147.969224 90)
		(property "Reference" "C935"
			(at 0 0 90)
			(layer "F.SilkS")
			(hide yes)
			(effects
				(font
					(size 1.27 1.27)
				)
			)
		)
		(property "Value" ""
			(at 0 0 90)
			(layer "F.Fab")
			(effects
				(font
					(size 1.27 1.27)
				)
			)
		)
		(duplicate_pad_numbers_are_jumpers no)
		(fp_line
			(start 1.524 -0.762)
			(end 1.524 0.762)
			(stroke
				(width 0.1524)
				(type default)
			)
			(layer "F.SilkS")
		)
		(fp_line
			(start -1.524 -0.762)
			(end 1.524 -0.762)
			(stroke
				(width 0.1524)
				(type default)
			)
			(layer "F.SilkS")
		)
		(fp_line
			(start 1.524 0.762)
			(end -1.524 0.762)
			(stroke
				(width 0.1524)
				(type default)
			)
			(layer "F.SilkS")
		)
		(fp_line
			(start -1.524 0.762)
			(end -1.524 -0.762)
			(stroke
				(width 0.1524)
				(type default)
			)
			(layer "F.SilkS")
		)
		(fp_line
			(start 1.1049 -0.724916)
			(end -1.1049 -0.724916)
			(stroke
				(width 0.1)
				(type default)
			)
			(layer "F.Fab")
		)
		(fp_line
			(start -1.1049 -0.724916)
			(end -1.1049 0.724916)
			(stroke
				(width 0.1)
				(type default)
			)
			(layer "F.Fab")
		)
		(fp_line
			(start 1.1049 0.724916)
			(end 1.1049 -0.724916)
			(stroke
				(width 0.1)
				(type default)
			)
			(layer "F.Fab")
		)
		(fp_line
			(start -1.1049 0.724916)
			(end 1.1049 0.724916)
			(stroke
				(width 0.1)
				(type default)
			)
			(layer "F.Fab")
		)
		(pad "1" smd rect
			(at -0.889 0 270)
			(size 1.016 1.27)
			(layers "F.Cu" "F.Mask" "F.Paste")
			(net "P12V_NIC6")
		)
		(pad "2" smd rect
			(at 0.889 0 270)
			(size 1.016 1.27)
			(layers "F.Cu" "F.Mask" "F.Paste")
			(net "GND")
		)
	)
)
